(kicad_pcb
	(version 20260206)
	(generator "pcbnew")
	(generator_version "10.0")
	(general
		(thickness 1.6)
		(legacy_teardrops no)
	)
	(paper "A4")
	(title_block
		(title "04192023_DAF0TMB3IC0_F0TG_MB_C_brd_V02_OCP.brd")
		(comment 1 "Grand Teton / footprints 1575-1581 of 8354")
	)
	(layers
		(0 "F.Cu" signal "TOP")
		(4 "In1.Cu" signal "GND")
		(6 "In2.Cu" signal "IN1")
		(8 "In3.Cu" signal "GND1")
		(10 "In4.Cu" signal "IN2")
		(12 "In5.Cu" signal "GND2")
		(14 "In6.Cu" signal "IN3")
		(16 "In7.Cu" signal "GND3")
		(18 "In8.Cu" signal "VCC")
		(20 "In9.Cu" signal "VCC1")
		(22 "In10.Cu" signal "GND4")
		(24 "In11.Cu" signal "IN4")
		(26 "In12.Cu" signal "GND5")
		(28 "In13.Cu" signal "IN5")
		(30 "In14.Cu" signal "GND6")
		(32 "In15.Cu" signal "IN6")
		(34 "In16.Cu" signal "GND7")
		(2 "B.Cu" signal "BOTTOM")
		(9 "F.Adhes" user "F.Adhesive")
		(11 "B.Adhes" user "B.Adhesive")
		(13 "F.Paste" user "Package Geometry/Pastemask Top")
		(15 "B.Paste" user "Package Geometry/Pastemask Bottom")
		(5 "F.SilkS" user "Ref Des/Silkscreen Top")
		(7 "B.SilkS" user "Ref Des/Silkscreen Bottom")
		(1 "F.Mask" user "Board Geometry/Soldermask Top")
		(3 "B.Mask" user "Board Geometry/Soldermask Bottom")
		(17 "Dwgs.User" user "User.Drawings")
		(19 "Cmts.User" user "User.Comments")
		(21 "Eco1.User" user "User.Eco1")
		(23 "Eco2.User" user "User.Eco2")
		(25 "Edge.Cuts" user "Board Geometry/Outline")
		(27 "Margin" user)
		(31 "F.CrtYd" user "Package Geometry/Place Bound Top")
		(29 "B.CrtYd" user "Package Geometry/Place Bound Bottom")
		(35 "F.Fab" user "Ref Des/Assembly Top")
		(33 "B.Fab" user "Ref Des/Assembly Bottom")
	)
	(footprint ""
		(layer "F.Cu")
		(at 171.598844 -419.800786 180)
		(property "Reference" "C7504"
			(at 0 0 180)
			(layer "F.SilkS")
			(hide yes)
			(effects
				(font
					(size 1.27 1.27)
				)
			)
		)
		(property "Value" ""
			(at 0 0 180)
			(layer "F.Fab")
			(effects
				(font
					(size 1.27 1.27)
				)
			)
		)
		(duplicate_pad_numbers_are_jumpers no)
		(fp_line
			(start 0.299974 0.150114)
			(end -0.299974 0.150114)
			(stroke
				(width 0.1)
				(type default)
			)
			(layer "F.Fab")
		)
		(fp_line
			(start 0.299974 -0.150114)
			(end 0.299974 0.150114)
			(stroke
				(width 0.1)
				(type default)
			)
			(layer "F.Fab")
		)
		(fp_line
			(start -0.299974 0.150114)
			(end -0.299974 -0.150114)
			(stroke
				(width 0.1)
				(type default)
			)
			(layer "F.Fab")
		)
		(fp_line
			(start -0.299974 -0.150114)
			(end 0.299974 -0.150114)
			(stroke
				(width 0.1)
				(type default)
			)
			(layer "F.Fab")
		)
		(pad "1" smd rect
			(at -0.2667 0 180)
			(size 0.3048 0.381)
			(layers "F.Cu" "F.Mask" "F.Paste")
			(net "P1V8_CPU1_RT_1D")
		)
		(pad "2" smd rect
			(at 0.2667 0 180)
			(size 0.3048 0.381)
			(layers "F.Cu" "F.Mask" "F.Paste")
			(net "GND")
		)
	)
	(footprint ""
		(layer "F.Cu")
		(at 352.373438 -169.413174 90)
		(property "Reference" "PC569_5"
			(at 0 0 90)
			(layer "F.SilkS")
			(hide yes)
			(effects
				(font
					(size 1.27 1.27)
				)
			)
		)
		(property "Value" ""
			(at 0 0 90)
			(layer "F.Fab")
			(effects
				(font
					(size 1.27 1.27)
				)
			)
		)
		(duplicate_pad_numbers_are_jumpers no)
		(fp_line
			(start 0.7874 -0.4064)
			(end 0.7874 0.4064)
			(stroke
				(width 0.1524)
				(type default)
			)
			(layer "F.SilkS")
		)
		(fp_line
			(start -0.7874 -0.4064)
			(end 0.7874 -0.4064)
			(stroke
				(width 0.1524)
				(type default)
			)
			(layer "F.SilkS")
		)
		(fp_line
			(start 0.7874 0.4064)
			(end -0.7874 0.4064)
			(stroke
				(width 0.1524)
				(type default)
			)
			(layer "F.SilkS")
		)
		(fp_line
			(start -0.7874 0.4064)
			(end -0.7874 -0.4064)
			(stroke
				(width 0.1524)
				(type default)
			)
			(layer "F.SilkS")
		)
		(fp_line
			(start -0.12065 -0.305054)
			(end -0.12065 -0.2794)
			(stroke
				(width 0.1)
				(type default)
			)
			(layer "F.Fab")
		)
		(fp_line
			(start -0.67945 -0.305054)
			(end -0.12065 -0.305054)
			(stroke
				(width 0.1)
				(type default)
			)
			(layer "F.Fab")
		)
		(fp_line
			(start 0.67945 -0.3048)
			(end 0.67945 0.3048)
			(stroke
				(width 0.1)
				(type default)
			)
			(layer "F.Fab")
		)
		(fp_line
			(start 0.12065 -0.3048)
			(end 0.67945 -0.3048)
			(stroke
				(width 0.1)
				(type default)
			)
			(layer "F.Fab")
		)
		(fp_line
			(start 0.12065 -0.2794)
			(end 0.12065 -0.3048)
			(stroke
				(width 0.1)
				(type default)
			)
			(layer "F.Fab")
		)
		(fp_line
			(start -0.12065 -0.2794)
			(end 0.12065 -0.2794)
			(stroke
				(width 0.1)
				(type default)
			)
			(layer "F.Fab")
		)
		(fp_line
			(start 0.120396 0.2794)
			(end -0.12065 0.2794)
			(stroke
				(width 0.1)
				(type default)
			)
			(layer "F.Fab")
		)
		(fp_line
			(start -0.12065 0.2794)
			(end -0.12065 0.3048)
			(stroke
				(width 0.1)
				(type default)
			)
			(layer "F.Fab")
		)
		(fp_line
			(start 0.67945 0.3048)
			(end 0.120396 0.3048)
			(stroke
				(width 0.1)
				(type default)
			)
			(layer "F.Fab")
		)
		(fp_line
			(start 0.120396 0.3048)
			(end 0.120396 0.2794)
			(stroke
				(width 0.1)
				(type default)
			)
			(layer "F.Fab")
		)
		(fp_line
			(start -0.12065 0.3048)
			(end -0.67945 0.3048)
			(stroke
				(width 0.1)
				(type default)
			)
			(layer "F.Fab")
		)
		(fp_line
			(start -0.67945 0.3048)
			(end -0.67945 -0.305054)
			(stroke
				(width 0.1)
				(type default)
			)
			(layer "F.Fab")
		)
		(pad "1" smd circle
			(at -0.40005 0 90)
			(size 0 0)
			(layers "F.Cu" "F.Mask" "F.Paste")
			(net "SW_P12V_AUX_PVDDCR_CPU0_P0_FLT")
		)
		(pad "2" smd circle
			(at 0.40005 0 90)
			(size 0 0)
			(layers "F.Cu" "F.Mask" "F.Paste")
			(net "GND")
		)
	)
	(footprint ""
		(layer "F.Cu")
		(at 439.821066 -388.8613)
		(property "Reference" "PR6530"
			(at 0 0 0)
			(layer "F.SilkS")
			(hide yes)
			(effects
				(font
					(size 1.27 1.27)
				)
			)
		)
		(property "Value" ""
			(at 0 0 0)
			(layer "F.Fab")
			(effects
				(font
					(size 1.27 1.27)
				)
			)
		)
		(duplicate_pad_numbers_are_jumpers no)
		(fp_line
			(start -0.7874 -0.4064)
			(end 0.7874 -0.4064)
			(stroke
				(width 0.1524)
				(type default)
			)
			(layer "F.SilkS")
		)
		(fp_line
			(start -0.7874 0.4064)
			(end -0.7874 -0.4064)
			(stroke
				(width 0.1524)
				(type default)
			)
			(layer "F.SilkS")
		)
		(fp_line
			(start 0.7874 -0.4064)
			(end 0.7874 0.4064)
			(stroke
				(width 0.1524)
				(type default)
			)
			(layer "F.SilkS")
		)
		(fp_line
			(start 0.7874 0.4064)
			(end -0.7874 0.4064)
			(stroke
				(width 0.1524)
				(type default)
			)
			(layer "F.SilkS")
		)
		(fp_line
			(start -0.67945 -0.305054)
			(end -0.12065 -0.305054)
			(stroke
				(width 0.1)
				(type default)
			)
			(layer "F.Fab")
		)
		(fp_line
			(start -0.67945 0.3048)
			(end -0.67945 -0.305054)
			(stroke
				(width 0.1)
				(type default)
			)
			(layer "F.Fab")
		)
		(fp_line
			(start -0.12065 -0.305054)
			(end -0.12065 -0.2794)
			(stroke
				(width 0.1)
				(type default)
			)
			(layer "F.Fab")
		)
		(fp_line
			(start -0.12065 -0.2794)
			(end 0.12065 -0.2794)
			(stroke
				(width 0.1)
				(type default)
			)
			(layer "F.Fab")
		)
		(fp_line
			(start -0.12065 0.2794)
			(end -0.12065 0.3048)
			(stroke
				(width 0.1)
				(type default)
			)
			(layer "F.Fab")
		)
		(fp_line
			(start -0.12065 0.3048)
			(end -0.67945 0.3048)
			(stroke
				(width 0.1)
				(type default)
			)
			(layer "F.Fab")
		)
		(fp_line
			(start 0.120396 0.2794)
			(end -0.12065 0.2794)
			(stroke
				(width 0.1)
				(type default)
			)
			(layer "F.Fab")
		)
		(fp_line
			(start 0.120396 0.3048)
			(end 0.120396 0.2794)
			(stroke
				(width 0.1)
				(type default)
			)
			(layer "F.Fab")
		)
		(fp_line
			(start 0.12065 -0.3048)
			(end 0.67945 -0.3048)
			(stroke
				(width 0.1)
				(type default)
			)
			(layer "F.Fab")
		)
		(fp_line
			(start 0.12065 -0.2794)
			(end 0.12065 -0.3048)
			(stroke
				(width 0.1)
				(type default)
			)
			(layer "F.Fab")
		)
		(fp_line
			(start 0.67945 -0.3048)
			(end 0.67945 0.3048)
			(stroke
				(width 0.1)
				(type default)
			)
			(layer "F.Fab")
		)
		(fp_line
			(start 0.67945 0.3048)
			(end 0.120396 0.3048)
			(stroke
				(width 0.1)
				(type default)
			)
			(layer "F.Fab")
		)
		(pad "1" smd circle
			(at -0.40005 0)
			(size 0 0)
			(layers "F.Cu" "F.Mask" "F.Paste")
			(net "P0V9_RETIMER_CPU0_SENSE_SH_P")
		)
		(pad "2" smd circle
			(at 0.40005 0)
			(size 0 0)
			(layers "F.Cu" "F.Mask" "F.Paste")
			(net "P0V9_CPU0_RT_2D")
		)
	)
	(footprint ""
		(layer "F.Cu")
		(at 396.125192 -330.862686 180)
		(property "Reference" "R464"
			(at 0 0 180)
			(layer "F.SilkS")
			(hide yes)
			(effects
				(font
					(size 1.27 1.27)
				)
			)
		)
		(property "Value" ""
			(at 0 0 180)
			(layer "F.Fab")
			(effects
				(font
					(size 1.27 1.27)
				)
			)
		)
		(duplicate_pad_numbers_are_jumpers no)
		(fp_line
			(start 0.7874 0.4064)
			(end -0.7874 0.4064)
			(stroke
				(width 0.1524)
				(type default)
			)
			(layer "F.SilkS")
		)
		(fp_line
			(start 0.7874 -0.4064)
			(end 0.7874 0.4064)
			(stroke
				(width 0.1524)
				(type default)
			)
			(layer "F.SilkS")
		)
		(fp_line
			(start -0.7874 0.4064)
			(end -0.7874 -0.4064)
			(stroke
				(width 0.1524)
				(type default)
			)
			(layer "F.SilkS")
		)
		(fp_line
			(start -0.7874 -0.4064)
			(end 0.7874 -0.4064)
			(stroke
				(width 0.1524)
				(type default)
			)
			(layer "F.SilkS")
		)
		(fp_line
			(start 0.67945 0.3048)
			(end 0.120396 0.3048)
			(stroke
				(width 0.1)
				(type default)
			)
			(layer "F.Fab")
		)
		(fp_line
			(start 0.67945 -0.3048)
			(end 0.67945 0.3048)
			(stroke
				(width 0.1)
				(type default)
			)
			(layer "F.Fab")
		)
		(fp_line
			(start 0.12065 -0.2794)
			(end 0.12065 -0.3048)
			(stroke
				(width 0.1)
				(type default)
			)
			(layer "F.Fab")
		)
		(fp_line
			(start 0.12065 -0.3048)
			(end 0.67945 -0.3048)
			(stroke
				(width 0.1)
				(type default)
			)
			(layer "F.Fab")
		)
		(fp_line
			(start 0.120396 0.3048)
			(end 0.120396 0.2794)
			(stroke
				(width 0.1)
				(type default)
			)
			(layer "F.Fab")
		)
		(fp_line
			(start 0.120396 0.2794)
			(end -0.12065 0.2794)
			(stroke
				(width 0.1)
				(type default)
			)
			(layer "F.Fab")
		)
		(fp_line
			(start -0.12065 0.3048)
			(end -0.67945 0.3048)
			(stroke
				(width 0.1)
				(type default)
			)
			(layer "F.Fab")
		)
		(fp_line
			(start -0.12065 0.2794)
			(end -0.12065 0.3048)
			(stroke
				(width 0.1)
				(type default)
			)
			(layer "F.Fab")
		)
		(fp_line
			(start -0.12065 -0.2794)
			(end 0.12065 -0.2794)
			(stroke
				(width 0.1)
				(type default)
			)
			(layer "F.Fab")
		)
		(fp_line
			(start -0.12065 -0.305054)
			(end -0.12065 -0.2794)
			(stroke
				(width 0.1)
				(type default)
			)
			(layer "F.Fab")
		)
		(fp_line
			(start -0.67945 0.3048)
			(end -0.67945 -0.305054)
			(stroke
				(width 0.1)
				(type default)
			)
			(layer "F.Fab")
		)
		(fp_line
			(start -0.67945 -0.305054)
			(end -0.12065 -0.305054)
			(stroke
				(width 0.1)
				(type default)
			)
			(layer "F.Fab")
		)
		(pad "1" smd circle
			(at -0.40005 0 180)
			(size 0 0)
			(layers "F.Cu" "F.Mask" "F.Paste")
			(net "SPI_CPU0_D0")
		)
		(pad "2" smd circle
			(at 0.40005 0 180)
			(size 0 0)
			(layers "F.Cu" "F.Mask" "F.Paste")
			(net "SPI_CPU0_R_D0")
		)
	)
	(footprint ""
		(layer "F.Cu")
		(at 205.181708 -117.748812)
		(property "Reference" "R3480"
			(at 0 0 0)
			(layer "F.SilkS")
			(hide yes)
			(effects
				(font
					(size 1.27 1.27)
				)
			)
		)
		(property "Value" ""
			(at 0 0 0)
			(layer "F.Fab")
			(effects
				(font
					(size 1.27 1.27)
				)
			)
		)
		(duplicate_pad_numbers_are_jumpers no)
		(fp_line
			(start -0.7874 -0.4064)
			(end 0.7874 -0.4064)
			(stroke
				(width 0.1524)
				(type default)
			)
			(layer "F.SilkS")
		)
		(fp_line
			(start -0.7874 0.4064)
			(end -0.7874 -0.4064)
			(stroke
				(width 0.1524)
				(type default)
			)
			(layer "F.SilkS")
		)
		(fp_line
			(start 0.7874 -0.4064)
			(end 0.7874 0.4064)
			(stroke
				(width 0.1524)
				(type default)
			)
			(layer "F.SilkS")
		)
		(fp_line
			(start 0.7874 0.4064)
			(end -0.7874 0.4064)
			(stroke
				(width 0.1524)
				(type default)
			)
			(layer "F.SilkS")
		)
		(fp_line
			(start -0.67945 -0.305054)
			(end -0.12065 -0.305054)
			(stroke
				(width 0.1)
				(type default)
			)
			(layer "F.Fab")
		)
		(fp_line
			(start -0.67945 0.3048)
			(end -0.67945 -0.305054)
			(stroke
				(width 0.1)
				(type default)
			)
			(layer "F.Fab")
		)
		(fp_line
			(start -0.12065 -0.305054)
			(end -0.12065 -0.2794)
			(stroke
				(width 0.1)
				(type default)
			)
			(layer "F.Fab")
		)
		(fp_line
			(start -0.12065 -0.2794)
			(end 0.12065 -0.2794)
			(stroke
				(width 0.1)
				(type default)
			)
			(layer "F.Fab")
		)
		(fp_line
			(start -0.12065 0.2794)
			(end -0.12065 0.3048)
			(stroke
				(width 0.1)
				(type default)
			)
			(layer "F.Fab")
		)
		(fp_line
			(start -0.12065 0.3048)
			(end -0.67945 0.3048)
			(stroke
				(width 0.1)
				(type default)
			)
			(layer "F.Fab")
		)
		(fp_line
			(start 0.120396 0.2794)
			(end -0.12065 0.2794)
			(stroke
				(width 0.1)
				(type default)
			)
			(layer "F.Fab")
		)
		(fp_line
			(start 0.120396 0.3048)
			(end 0.120396 0.2794)
			(stroke
				(width 0.1)
				(type default)
			)
			(layer "F.Fab")
		)
		(fp_line
			(start 0.12065 -0.3048)
			(end 0.67945 -0.3048)
			(stroke
				(width 0.1)
				(type default)
			)
			(layer "F.Fab")
		)
		(fp_line
			(start 0.12065 -0.2794)
			(end 0.12065 -0.3048)
			(stroke
				(width 0.1)
				(type default)
			)
			(layer "F.Fab")
		)
		(fp_line
			(start 0.67945 -0.3048)
			(end 0.67945 0.3048)
			(stroke
				(width 0.1)
				(type default)
			)
			(layer "F.Fab")
		)
		(fp_line
			(start 0.67945 0.3048)
			(end 0.120396 0.3048)
			(stroke
				(width 0.1)
				(type default)
			)
			(layer "F.Fab")
		)
		(pad "1" smd circle
			(at -0.40005 0)
			(size 0 0)
			(layers "F.Cu" "F.Mask" "F.Paste")
			(net "GPU_BASE_HMC_READY_ISO_R")
		)
		(pad "2" smd circle
			(at 0.40005 0)
			(size 0 0)
			(layers "F.Cu" "F.Mask" "F.Paste")
			(net "GPU_BASE_HMC_READY_ISO")
		)
	)
	(footprint ""
		(layer "F.Cu")
		(at 209.959956 -37.769292 90)
		(property "Reference" "C2014"
			(at 0 0 90)
			(layer "F.SilkS")
			(hide yes)
			(effects
				(font
					(size 1.27 1.27)
				)
			)
		)
		(property "Value" ""
			(at 0 0 90)
			(layer "F.Fab")
			(effects
				(font
					(size 1.27 1.27)
				)
			)
		)
		(duplicate_pad_numbers_are_jumpers no)
		(fp_line
			(start 0.7874 -0.4064)
			(end 0.7874 0.4064)
			(stroke
				(width 0.1524)
				(type default)
			)
			(layer "F.SilkS")
		)
		(fp_line
			(start -0.7874 -0.4064)
			(end 0.7874 -0.4064)
			(stroke
				(width 0.1524)
				(type default)
			)
			(layer "F.SilkS")
		)
		(fp_line
			(start 0.7874 0.4064)
			(end -0.7874 0.4064)
			(stroke
				(width 0.1524)
				(type default)
			)
			(layer "F.SilkS")
		)
		(fp_line
			(start -0.7874 0.4064)
			(end -0.7874 -0.4064)
			(stroke
				(width 0.1524)
				(type default)
			)
			(layer "F.SilkS")
		)
		(fp_line
			(start -0.12065 -0.305054)
			(end -0.12065 -0.2794)
			(stroke
				(width 0.1)
				(type default)
			)
			(layer "F.Fab")
		)
		(fp_line
			(start -0.67945 -0.305054)
			(end -0.12065 -0.305054)
			(stroke
				(width 0.1)
				(type default)
			)
			(layer "F.Fab")
		)
		(fp_line
			(start 0.67945 -0.3048)
			(end 0.67945 0.3048)
			(stroke
				(width 0.1)
				(type default)
			)
			(layer "F.Fab")
		)
		(fp_line
			(start 0.12065 -0.3048)
			(end 0.67945 -0.3048)
			(stroke
				(width 0.1)
				(type default)
			)
			(layer "F.Fab")
		)
		(fp_line
			(start 0.12065 -0.2794)
			(end 0.12065 -0.3048)
			(stroke
				(width 0.1)
				(type default)
			)
			(layer "F.Fab")
		)
		(fp_line
			(start -0.12065 -0.2794)
			(end 0.12065 -0.2794)
			(stroke
				(width 0.1)
				(type default)
			)
			(layer "F.Fab")
		)
		(fp_line
			(start 0.120396 0.2794)
			(end -0.12065 0.2794)
			(stroke
				(width 0.1)
				(type default)
			)
			(layer "F.Fab")
		)
		(fp_line
			(start -0.12065 0.2794)
			(end -0.12065 0.3048)
			(stroke
				(width 0.1)
				(type default)
			)
			(layer "F.Fab")
		)
		(fp_line
			(start 0.67945 0.3048)
			(end 0.120396 0.3048)
			(stroke
				(width 0.1)
				(type default)
			)
			(layer "F.Fab")
		)
		(fp_line
			(start 0.120396 0.3048)
			(end 0.120396 0.2794)
			(stroke
				(width 0.1)
				(type default)
			)
			(layer "F.Fab")
		)
		(fp_line
			(start -0.12065 0.3048)
			(end -0.67945 0.3048)
			(stroke
				(width 0.1)
				(type default)
			)
			(layer "F.Fab")
		)
		(fp_line
			(start -0.67945 0.3048)
			(end -0.67945 -0.305054)
			(stroke
				(width 0.1)
				(type default)
			)
			(layer "F.Fab")
		)
		(pad "1" smd circle
			(at -0.40005 0 90)
			(size 0 0)
			(layers "F.Cu" "F.Mask" "F.Paste")
			(net "P3V3_AUX")
		)
		(pad "2" smd circle
			(at 0.40005 0 90)
			(size 0 0)
			(layers "F.Cu" "F.Mask" "F.Paste")
			(net "GND")
		)
	)
	(footprint ""
		(layer "F.Cu")
		(at 427.5836 -17.624298 90)
		(property "Reference" "C1575"
			(at 0 0 90)
			(layer "F.SilkS")
			(hide yes)
			(effects
				(font
					(size 1.27 1.27)
				)
			)
		)
		(property "Value" ""
			(at 0 0 90)
			(layer "F.Fab")
			(effects
				(font
					(size 1.27 1.27)
				)
			)
		)
		(duplicate_pad_numbers_are_jumpers no)
		(fp_line
			(start 0.299974 -0.150114)
			(end 0.299974 0.150114)
			(stroke
				(width 0.1)
				(type default)
			)
			(layer "F.Fab")
		)
		(fp_line
			(start -0.299974 -0.150114)
			(end 0.299974 -0.150114)
			(stroke
				(width 0.1)
				(type default)
			)
			(layer "F.Fab")
		)
		(fp_line
			(start 0.299974 0.150114)
			(end -0.299974 0.150114)
			(stroke
				(width 0.1)
				(type default)
			)
			(layer "F.Fab")
		)
		(fp_line
			(start -0.299974 0.150114)
			(end -0.299974 -0.150114)
			(stroke
				(width 0.1)
				(type default)
			)
			(layer "F.Fab")
		)
		(pad "1" smd rect
			(at -0.2667 0 90)
			(size 0.3048 0.381)
			(layers "F.Cu" "F.Mask" "F.Paste")
			(net "P5E_CPU0_G3_TX_C_DP<2>")
		)
		(pad "2" smd rect
			(at 0.2667 0 90)
			(size 0.3048 0.381)
			(layers "F.Cu" "F.Mask" "F.Paste")
			(net "P5E_CPU0_G3_TX_DP<2>")
		)
	)
)
